(kicad_pcb
	(version 20260206)
	(generator "pcbnew")
	(generator_version "10.0")
	(general
		(thickness 1.6)
		(legacy_teardrops no)
	)
	(paper "A4")
	(title_block
		(title "netronome-mezz — pcbd0082-001_rev01_jul9_a.brd")
		(comment 1 "Open CloudServer (Microsoft) / footprints 203-205 of 714")
	)
	(layers
		(0 "F.Cu" signal "TOP")
		(4 "In1.Cu" signal "02_GND")
		(6 "In2.Cu" signal "03_SIG")
		(8 "In3.Cu" signal "04_SIG")
		(10 "In4.Cu" signal "05_GND")
		(12 "In5.Cu" signal "06_PWR1")
		(14 "In6.Cu" signal "07_SIG")
		(16 "In7.Cu" signal "08_SIG")
		(18 "In8.Cu" signal "09_GND")
		(2 "B.Cu" signal "BOTTOM")
		(9 "F.Adhes" user "F.Adhesive")
		(11 "B.Adhes" user "B.Adhesive")
		(13 "F.Paste" user "Package Geometry/Pastemask Top")
		(15 "B.Paste" user "Package Geometry/Pastemask Bottom")
		(5 "F.SilkS" user "Ref Des/Silkscreen Top")
		(7 "B.SilkS" user "Ref Des/Silkscreen Bottom")
		(1 "F.Mask" user "Board Geometry/Soldermask Top")
		(3 "B.Mask" user "Board Geometry/Soldermask Bottom")
		(17 "Dwgs.User" user "User.Drawings")
		(19 "Cmts.User" user "User.Comments")
		(21 "Eco1.User" user "User.Eco1")
		(23 "Eco2.User" user "User.Eco2")
		(25 "Edge.Cuts" user "Board Geometry/Outline")
		(27 "Margin" user)
		(31 "F.CrtYd" user "Package Geometry/Place Bound Top")
		(29 "B.CrtYd" user "Package Geometry/Place Bound Bottom")
		(35 "F.Fab" user "Ref Des/Assembly Top")
		(33 "B.Fab" user "Ref Des/Assembly Bottom")
		(45 "User.4" user "COMPVAL_TYPE_BOTTOM")
	)
	(footprint ""
		(layer "F.Cu")
		(at 25.2857 40.894)
		(property "Reference" "C82"
			(at 0 0 0)
			(layer "F.SilkS")
			(hide yes)
			(effects
				(font
					(size 1.27 1.27)
				)
			)
		)
		(property "Value" "1500PF"
			(at -0.091846 0.2921 90)
			(unlocked yes)
			(layer "F.Fab")
			(hide yes)
			(effects
				(font
					(size 0.7874 0.5842)
					(thickness 0.2032)
				)
				(justify left)
			)
		)
		(property "Device Type" "CAPC0088"
			(at -0.091846 0.2921 90)
			(unlocked yes)
			(layer "F.Fab")
			(hide yes)
			(effects
				(font
					(size 0.7874 0.5842)
					(thickness 0.2032)
				)
				(justify left)
			)
		)
		(duplicate_pad_numbers_are_jumpers no)
		(fp_poly
			(pts
				(xy 0.635 1.0668) (xy 0.635 -1.0668) (xy -0.635 -1.0668) (xy -0.635 1.0668)
			)
			(stroke
				(width 0)
				(type default)
			)
			(fill no)
			(layer "F.CrtYd")
		)
		(fp_line
			(start -0.254 -0.508)
			(end 0.254 -0.508)
			(stroke
				(width 0.0254)
				(type default)
			)
			(layer "F.Fab")
		)
		(fp_line
			(start -0.254 0.508)
			(end -0.254 -0.508)
			(stroke
				(width 0.0254)
				(type default)
			)
			(layer "F.Fab")
		)
		(fp_line
			(start 0.254 -0.508)
			(end 0.254 0.508)
			(stroke
				(width 0.0254)
				(type default)
			)
			(layer "F.Fab")
		)
		(fp_line
			(start 0.254 0.508)
			(end -0.254 0.508)
			(stroke
				(width 0.0254)
				(type default)
			)
			(layer "F.Fab")
		)
		(pad "1" smd rect
			(at 0 -0.4191)
			(size 0.508 0.5334)
			(layers "F.Cu" "F.Mask" "F.Paste")
			(net "NFP_VDD_CORE_SENSE_VSS")
		)
		(pad "2" smd rect
			(at 0 0.4191)
			(size 0.508 0.5334)
			(layers "F.Cu" "F.Mask" "F.Paste")
			(net "GND")
		)
		(zone
			(layer "F.Cu")
			(hatch none 0.5)
			(connect_pads
				(clearance 0)
			)
			(min_thickness 0.25)
			(keepout
				(tracks not_allowed)
				(vias allowed)
				(pads allowed)
				(copperpour not_allowed)
				(footprints allowed)
			)
			(placement
				(enabled no)
				(sheetname "")
			)
			(fill
				(thermal_gap 0.5)
				(thermal_bridge_width 0.5)
				(island_removal_mode 0)
			)
			(polygon
				(pts
					(xy 25.3111 40.8686) (xy 25.3111 40.9194) (xy 25.2603 40.9194) (xy 25.2603 40.8686)
				)
			)
		)
	)
	(footprint ""
		(layer "F.Cu")
		(at 83.185 47.625 90)
		(property "Reference" "Q1"
			(at 1.62433 2.159 0)
			(unlocked yes)
			(layer "F.SilkS")
			(effects
				(font
					(size 0.7874 0.5842)
					(thickness 0.127)
				)
				(justify left)
			)
		)
		(property "Value" "*"
			(at -0.4826 -0.148107 90)
			(unlocked yes)
			(layer "F.Fab")
			(hide yes)
			(effects
				(font
					(size 1.27 0.9652)
					(thickness 0.000001)
				)
				(justify left)
			)
		)
		(property "Device Type" "TRAN0028"
			(at -0.4826 -0.148107 90)
			(unlocked yes)
			(layer "F.Fab")
			(hide yes)
			(effects
				(font
					(size 1.27 0.9652)
					(thickness 0.000001)
				)
				(justify left)
			)
		)
		(duplicate_pad_numbers_are_jumpers no)
		(fp_line
			(start 1.905 -1.905)
			(end -1.905 -1.905)
			(stroke
				(width 0.1524)
				(type default)
			)
			(layer "F.SilkS")
		)
		(fp_line
			(start -0.7112 -1.905)
			(end -1.905 -1.905)
			(stroke
				(width 0.1524)
				(type default)
			)
			(layer "F.SilkS")
		)
		(fp_line
			(start -1.905 -1.905)
			(end -1.905 -1.524)
			(stroke
				(width 0.1524)
				(type default)
			)
			(layer "F.SilkS")
		)
		(fp_line
			(start 1.905 -1.524)
			(end 1.905 -1.905)
			(stroke
				(width 0.1524)
				(type default)
			)
			(layer "F.SilkS")
		)
		(fp_line
			(start -1.905 1.524)
			(end -1.905 1.905)
			(stroke
				(width 0.1524)
				(type default)
			)
			(layer "F.SilkS")
		)
		(fp_line
			(start 1.905 1.905)
			(end 1.905 1.524)
			(stroke
				(width 0.1524)
				(type default)
			)
			(layer "F.SilkS")
		)
		(fp_line
			(start -1.378915 1.905)
			(end 1.905 1.905)
			(stroke
				(width 0.1524)
				(type default)
			)
			(layer "F.SilkS")
		)
		(fp_line
			(start -1.905 1.905)
			(end 1.905 1.905)
			(stroke
				(width 0.1524)
				(type default)
			)
			(layer "F.SilkS")
		)
		(fp_arc
			(start -2.7178 -1.1684)
			(mid -2.717421 -1.182162)
			(end -2.716301 -1.195883)
			(stroke
				(width 0.1524)
				(type default)
			)
			(layer "F.SilkS")
		)
		(fp_arc
			(start -2.70571 -1.090905)
			(mid -2.714762 -1.129183)
			(end -2.7178 -1.1684)
			(stroke
				(width 0.1524)
				(type default)
			)
			(layer "F.SilkS")
		)
		(fp_circle
			(center -2.4638 -1.1684)
			(end -2.4638 -0.9144)
			(stroke
				(width 0.1524)
				(type default)
			)
			(fill no)
			(layer "F.SilkS")
		)
		(fp_poly
			(pts
				(xy -2.0066 -1.17856) (xy -2.0066 -0.77216) (xy -1.1938 -0.77216) (xy -1.1938 -1.17856)
			)
			(stroke
				(width 0)
				(type default)
			)
			(fill yes)
			(layer "F.Paste")
		)
		(fp_poly
			(pts
				(xy 0.1524 -0.635) (xy 0.762 -0.635) (xy 0.762 -1.2446) (xy 0.1524 -1.2446)
			)
			(stroke
				(width 0)
				(type default)
			)
			(fill yes)
			(layer "F.Paste")
		)
		(fp_poly
			(pts
				(xy -0.1524 -0.635) (xy -0.762 -0.635) (xy -0.762 -1.2446) (xy -0.1524 -1.2446)
			)
			(stroke
				(width 0)
				(type default)
			)
			(fill yes)
			(layer "F.Paste")
		)
		(fp_poly
			(pts
				(xy -2.0066 -0.52832) (xy -2.0066 -0.12192) (xy -1.1938 -0.12192) (xy -1.1938 -0.52832)
			)
			(stroke
				(width 0)
				(type default)
			)
			(fill yes)
			(layer "F.Paste")
		)
		(fp_poly
			(pts
				(xy 0.1524 0.3302) (xy 0.762 0.3302) (xy 0.762 -0.3302) (xy 0.1524 -0.3302)
			)
			(stroke
				(width 0)
				(type default)
			)
			(fill yes)
			(layer "F.Paste")
		)
		(fp_poly
			(pts
				(xy -0.1524 0.3302) (xy -0.762 0.3302) (xy -0.762 -0.3302) (xy -0.1524 -0.3302)
			)
			(stroke
				(width 0)
				(type default)
			)
			(fill yes)
			(layer "F.Paste")
		)
		(fp_poly
			(pts
				(xy 0.1524 0.635) (xy 0.762 0.635) (xy 0.762 1.2446) (xy 0.1524 1.2446)
			)
			(stroke
				(width 0)
				(type default)
			)
			(fill yes)
			(layer "F.Paste")
		)
		(fp_poly
			(pts
				(xy -0.1524 0.635) (xy -0.762 0.635) (xy -0.762 1.2446) (xy -0.1524 1.2446)
			)
			(stroke
				(width 0)
				(type default)
			)
			(fill yes)
			(layer "F.Paste")
		)
		(fp_poly
			(pts
				(xy -2.54 1.752194) (xy 2.54 1.752194) (xy 2.54 -2.286) (xy -2.54 -2.286)
			)
			(stroke
				(width 0)
				(type default)
			)
			(fill no)
			(layer "F.CrtYd")
		)
		(fp_line
			(start 1.7018 -1.7018)
			(end -1.7018 -1.7018)
			(stroke
				(width 0.1524)
				(type default)
			)
			(layer "F.Fab")
		)
		(fp_line
			(start -1.7018 -1.7018)
			(end -1.7018 1.7018)
			(stroke
				(width 0.1524)
				(type default)
			)
			(layer "F.Fab")
		)
		(fp_line
			(start 1.7018 1.7018)
			(end 1.7018 -1.7018)
			(stroke
				(width 0.1524)
				(type default)
			)
			(layer "F.Fab")
		)
		(fp_line
			(start -1.7018 1.7018)
			(end 1.7018 1.7018)
			(stroke
				(width 0.1524)
				(type default)
			)
			(layer "F.Fab")
		)
		(fp_circle
			(center -1.27 -1.27)
			(end -1.27 -1.016)
			(stroke
				(width 0.1524)
				(type default)
			)
			(fill no)
			(layer "F.Fab")
		)
		(pad "1" smd custom
			(at -1.6002 -0.97536 90)
			(size 0.2032 0.2032)
			(layers "F.Cu" "F.Mask" "F.Paste")
			(net "EXT_12.0V")
			(options
				(clearance outline)
				(anchor circle)
			)
			(primitives
				(gr_poly
					(pts
						(xy -0.4064 0.52832) (xy 0.4064 0.52832) (xy 0.4064 -0.52832) (xy -0.4064 -0.52832) (xy -0.4064 -0.12192)
						(xy 0.1778 -0.12192) (xy 0.1778 0.12192) (xy -0.4064 0.12192)
					)
					(width 0)
					(fill yes)
				)
			)
		)
		(pad "2" smd circle
			(at -1.524 -0.381 90)
			(size 0 0)
			(layers "F.Cu" "F.Mask" "F.Paste")
			(net "EXT_12.0V")
			(padstack
				(mode custom)
				(layer "In1.Cu"
					(shape circle)
					(size 0 0)
					(zone_connect -1)
				)
				(layer "In2.Cu"
					(shape circle)
					(size 0 0)
					(zone_connect -1)
				)
				(layer "In3.Cu"
					(shape circle)
					(size 0 0)
					(zone_connect -1)
				)
				(layer "In4.Cu"
					(shape circle)
					(size 0 0)
					(zone_connect -1)
				)
				(layer "In5.Cu"
					(shape circle)
					(size 0 0)
					(zone_connect -1)
				)
				(layer "In6.Cu"
					(shape circle)
					(size 0 0)
					(zone_connect -1)
				)
				(layer "In7.Cu"
					(shape circle)
					(size 0 0)
					(zone_connect -1)
				)
				(layer "In8.Cu"
					(shape circle)
					(size 0 0)
					(zone_connect -1)
				)
				(layer "B.Cu"
					(shape circle)
					(size 0 0)
					(zone_connect -1)
				)
			)
		)
		(pad "3" smd rect
			(at -1.6002 0.32512 90)
			(size 0.8128 0.4064)
			(layers "F.Cu" "F.Mask" "F.Paste")
			(net "11N2173")
		)
		(pad "4" smd rect
			(at -1.6002 0.97536 90)
			(size 0.8128 0.4064)
			(layers "F.Cu" "F.Mask" "F.Paste")
			(net "11N2175")
		)
		(pad "5" smd rect
			(at 1.6002 0.97536 270)
			(size 0.8128 0.4064)
			(layers "F.Cu" "F.Mask" "F.Paste")
			(net "11N2177")
		)
		(pad "6" smd rect
			(at 1.6002 0.32512 270)
			(size 0.8128 0.4064)
			(layers "F.Cu" "F.Mask" "F.Paste")
			(net "11N2253")
		)
		(pad "7" smd rect
			(at 1.6002 -0.32512 270)
			(size 0.8128 0.4064)
			(layers "F.Cu" "F.Mask" "F.Paste")
			(net "11N2253")
		)
		(pad "8" smd rect
			(at 1.6002 -0.97536 270)
			(size 0.8128 0.4064)
			(layers "F.Cu" "F.Mask" "F.Paste")
			(net "11N2253")
		)
		(pad "9" smd rect
			(at 0 0 90)
			(size 1.778 2.7432)
			(layers "F.Cu" "F.Mask" "F.Paste")
			(net "GND")
		)
		(zone
			(layer "F.Cu")
			(hatch none 0.5)
			(connect_pads
				(clearance 0)
			)
			(min_thickness 0.25)
			(keepout
				(tracks allowed)
				(vias not_allowed)
				(pads allowed)
				(copperpour not_allowed)
				(footprints allowed)
			)
			(placement
				(enabled no)
				(sheetname "")
			)
			(fill
				(thermal_gap 0.5)
				(thermal_bridge_width 0.5)
				(island_removal_mode 0)
			)
			(polygon
				(pts
					(xy 81.28 46.736) (xy 81.28 48.514) (xy 81.661 48.514) (xy 81.661 46.736)
				)
			)
		)
		(zone
			(layer "F.Cu")
			(hatch none 0.5)
			(connect_pads
				(clearance 0)
			)
			(min_thickness 0.25)
			(keepout
				(tracks allowed)
				(vias not_allowed)
				(pads allowed)
				(copperpour not_allowed)
				(footprints allowed)
			)
			(placement
				(enabled no)
				(sheetname "")
			)
			(fill
				(thermal_gap 0.5)
				(thermal_bridge_width 0.5)
				(island_removal_mode 0)
			)
			(polygon
				(pts
					(xy 85.09 48.514) (xy 85.09 46.736) (xy 84.709 46.736) (xy 84.709 48.514)
				)
			)
		)
		(zone
			(layer "F.Cu")
			(hatch none 0.5)
			(connect_pads
				(clearance 0)
			)
			(min_thickness 0.25)
			(keepout
				(tracks allowed)
				(vias not_allowed)
				(pads allowed)
				(copperpour not_allowed)
				(footprints allowed)
			)
			(placement
				(enabled no)
				(sheetname "")
			)
			(fill
				(thermal_gap 0.5)
				(thermal_bridge_width 0.5)
				(island_removal_mode 0)
			)
			(polygon
				(pts
					(arc
						(start 82.3468 50.0888)
						(mid 81.6864 50.0888)
						(end 82.3468 50.0888)
					)
				)
			)
		)
	)
	(footprint ""
		(layer "F.Cu")
		(at 27.178 11.557 -90)
		(property "Reference" "R138"
			(at 0 0 270)
			(layer "F.SilkS")
			(hide yes)
			(effects
				(font
					(size 1.27 1.27)
				)
			)
		)
		(property "Value" "0"
			(at -0.148158 1.3462 0)
			(unlocked yes)
			(layer "F.Fab")
			(hide yes)
			(effects
				(font
					(size 1.27 0.9652)
					(thickness 0.000001)
				)
				(justify left)
			)
		)
		(property "Device Type" "REST1111"
			(at -0.148158 1.3462 0)
			(unlocked yes)
			(layer "F.Fab")
			(hide yes)
			(effects
				(font
					(size 1.27 0.9652)
					(thickness 0.000001)
				)
				(justify left)
			)
		)
		(duplicate_pad_numbers_are_jumpers no)
		(fp_poly
			(pts
				(xy 0.635 1.0668) (xy 0.635 -1.0668) (xy -0.635 -1.0668) (xy -0.635 1.0668)
			)
			(stroke
				(width 0)
				(type default)
			)
			(fill no)
			(layer "F.CrtYd")
		)
		(fp_line
			(start -0.254 0.508)
			(end -0.254 -0.508)
			(stroke
				(width 0.0254)
				(type default)
			)
			(layer "F.Fab")
		)
		(fp_line
			(start 0.254 0.508)
			(end -0.254 0.508)
			(stroke
				(width 0.0254)
				(type default)
			)
			(layer "F.Fab")
		)
		(fp_line
			(start -0.254 -0.508)
			(end 0.254 -0.508)
			(stroke
				(width 0.0254)
				(type default)
			)
			(layer "F.Fab")
		)
		(fp_line
			(start 0.254 -0.508)
			(end 0.254 0.508)
			(stroke
				(width 0.0254)
				(type default)
			)
			(layer "F.Fab")
		)
		(pad "1" smd rect
			(at 0 -0.4191 270)
			(size 0.508 0.5334)
			(layers "F.Cu" "F.Mask" "F.Paste")
			(net "_PSU_I2C_SCL")
		)
		(pad "2" smd rect
			(at 0 0.4191 270)
			(size 0.508 0.5334)
			(layers "F.Cu" "F.Mask" "F.Paste")
			(net "PSU_I2C_SCL")
		)
		(zone
			(layer "F.Cu")
			(hatch none 0.5)
			(connect_pads
				(clearance 0)
			)
			(min_thickness 0.25)
			(keepout
				(tracks not_allowed)
				(vias allowed)
				(pads allowed)
				(copperpour not_allowed)
				(footprints allowed)
			)
			(placement
				(enabled no)
				(sheetname "")
			)
			(fill
				(thermal_gap 0.5)
				(thermal_bridge_width 0.5)
				(island_removal_mode 0)
			)
			(polygon
				(pts
					(xy 27.2034 11.5824) (xy 27.1526 11.5824) (xy 27.1526 11.5316) (xy 27.2034 11.5316)
				)
			)
		)
	)
)
